# BASEBOARD_FAB2 (Tioga Pass) — schematic netlist excerpt (pin names and nets, part order shuffled) for the footprints in the layout excerpt that follows; sources: Cadence DE-HDL packaged netlist, KiCad conversion of Wiwynn_Tioga_Pass_MB.brd

CR1L1  DIODE  1N4148W IC  pkg SM  page 168 : C = FM_DB_UART_SEL1_N ; A = FM_DB_UART_SEL0_N

(kicad_pcb
	(version 20260206)
	(generator "pcbnew")
	(generator_version "10.0")
	(general
		(thickness 1.6)
		(legacy_teardrops no)
	)
	(paper "A4")
	(title_block
		(title "Wiwynn_Tioga_Pass_MB.brd")
		(comment 1 "Tioga Pass / footprints 2987-2987 of 4770")
	)
	(layers
		(0 "F.Cu" signal "TOP")
		(4 "In1.Cu" signal "L2GND")
		(6 "In2.Cu" signal "L3")
		(8 "In3.Cu" signal "L4GND")
		(10 "In4.Cu" signal "L5")
		(12 "In5.Cu" signal "L6GND")
		(14 "In6.Cu" signal "L7VCC")
		(16 "In7.Cu" signal "L8VCC")
		(18 "In8.Cu" signal "L9GND")
		(20 "In9.Cu" signal "L10")
		(22 "In10.Cu" signal "L11GND")
		(24 "In11.Cu" signal "L12")
		(26 "In12.Cu" signal "L13GND")
		(2 "B.Cu" signal "BOTTOM")
		(9 "F.Adhes" user "F.Adhesive")
		(11 "B.Adhes" user "B.Adhesive")
		(13 "F.Paste" user "Package Geometry/Pastemask Top")
		(15 "B.Paste" user "Package Geometry/Pastemask Bottom")
		(5 "F.SilkS" user "Ref Des/Silkscreen Top")
		(7 "B.SilkS" user "Ref Des/Silkscreen Bottom")
		(1 "F.Mask" user "Board Geometry/Soldermask Top")
		(3 "B.Mask" user "Board Geometry/Soldermask Bottom")
		(17 "Dwgs.User" user "User.Drawings")
		(19 "Cmts.User" user "User.Comments")
		(21 "Eco1.User" user "User.Eco1")
		(23 "Eco2.User" user "User.Eco2")
		(25 "Edge.Cuts" user "Board Geometry/Outline")
		(27 "Margin" user)
		(31 "F.CrtYd" user "Package Geometry/Place Bound Top")
		(29 "B.CrtYd" user "Package Geometry/Place Bound Bottom")
		(35 "F.Fab" user "Ref Des/Assembly Top")
		(33 "B.Fab" user "Ref Des/Assembly Bottom")
	)
	(footprint ""
		(layer "B.Cu")
		(at 484.124 -150.0378 90)
		(property "Reference" "CR1L1"
			(at 0 0 90)
			(layer "B.SilkS")
			(hide yes)
			(effects
				(font
					(size 1.27 1.27)
				)
				(justify mirror)
			)
		)
		(property "Value" ""
			(at 0 0 90)
			(layer "B.Fab")
			(effects
				(font
					(size 1.27 1.27)
				)
				(justify mirror)
			)
		)
		(duplicate_pad_numbers_are_jumpers no)
		(fp_line
			(start 0.9144 0.1016)
			(end 0.9144 2.9464)
			(stroke
				(width 0.1524)
				(type default)
			)
			(layer "B.SilkS")
		)
		(fp_line
			(start 0.8382 0.1016)
			(end 0.9144 0.1016)
			(stroke
				(width 0.1524)
				(type default)
			)
			(layer "B.SilkS")
		)
		(fp_line
			(start -0.8382 0.1016)
			(end -0.9144 0.1016)
			(stroke
				(width 0.1524)
				(type default)
			)
			(layer "B.SilkS")
		)
		(fp_line
			(start -0.9144 0.1016)
			(end -0.9144 2.9464)
			(stroke
				(width 0.1524)
				(type default)
			)
			(layer "B.SilkS")
		)
		(fp_line
			(start 0.9144 2.9464)
			(end 0.8382 2.9464)
			(stroke
				(width 0.1524)
				(type default)
			)
			(layer "B.SilkS")
		)
		(fp_line
			(start -0.9144 2.9464)
			(end -0.8382 2.9464)
			(stroke
				(width 0.1524)
				(type default)
			)
			(layer "B.SilkS")
		)
		(fp_circle
			(center -1.128776 -0.907288)
			(end -1.128776 -0.780288)
			(stroke
				(width 0.254)
				(type default)
			)
			(fill no)
			(layer "B.SilkS")
		)
		(fp_poly
			(pts
				(xy 0 0.1016) (xy -0.5334 0.1016) (xy -0.7366 0.1016) (xy -0.9144 0.1016) (xy -0.9144 2.9464) (xy -0.8382 2.9464)
				(xy -0.762 2.9464) (xy 0.9144 2.9464) (xy 0.9144 2.7686) (xy 0.9144 2.159) (xy 0.9144 0.1016) (xy 0.7366 0.1016)
				(xy 0.5842 0.1016)
			)
			(stroke
				(width 0)
				(type default)
			)
			(fill no)
			(layer "B.CrtYd")
		)
		(fp_line
			(start 0.9144 0.1016)
			(end 0.9144 2.9464)
			(stroke
				(width 0.1)
				(type default)
			)
			(layer "B.Fab")
		)
		(fp_line
			(start -0.9144 0.1016)
			(end 0.9144 0.1016)
			(stroke
				(width 0.1)
				(type default)
			)
			(layer "B.Fab")
		)
		(fp_line
			(start 0.9144 2.9464)
			(end -0.9144 2.9464)
			(stroke
				(width 0.1)
				(type default)
			)
			(layer "B.Fab")
		)
		(fp_line
			(start -0.9144 2.9464)
			(end -0.9144 0.1016)
			(stroke
				(width 0.1)
				(type default)
			)
			(layer "B.Fab")
		)
		(fp_circle
			(center -1.128776 -0.907288)
			(end -1.128776 -0.780288)
			(stroke
				(width 0.254)
				(type default)
			)
			(fill no)
			(layer "B.Fab")
		)
		(pad "1" smd rect
			(at 0 0)
			(size 1.524 0.762)
			(layers "B.Cu" "B.Mask" "B.Paste")
			(net "FM_DB_UART_SEL1_N")
		)
		(pad "2" smd rect
			(at 0 3.048 180)
			(size 1.524 0.762)
			(layers "B.Cu" "B.Mask" "B.Paste")
			(net "FM_DB_UART_SEL0_N")
		)
	)
)
